# T6G (Grand Teton) — schematic netlist excerpt (pin names and nets, part order shuffled) for the footprints in the layout excerpt that follows; sources: Cadence DE-HDL packaged netlist, KiCad conversion of 04192023_DAF0TMB3IC0_F0TG_MB_C_brd_V02_OCP.brd

R2844  Q_RES  33.2 1% CHIP  pkg 0402LF  page 81 : A = FM_SWB_BIC_READY_ISO_R_N ; B = FM_SWB_BIC_READY_ISO_N
R4164  Q_RES  4.7K 5% CHIP  pkg 0402LF  page 124 : A = P3V3_AUX ; B = GPU_3V3IO_RSVD1_N

(kicad_pcb
	(version 20260206)
	(generator "pcbnew")
	(generator_version "10.0")
	(general
		(thickness 1.6)
		(legacy_teardrops no)
	)
	(paper "A4")
	(title_block
		(title "04192023_DAF0TMB3IC0_F0TG_MB_C_brd_V02_OCP.brd")
		(comment 1 "Grand Teton / footprints 588-589 of 8354")
	)
	(layers
		(0 "F.Cu" signal "TOP")
		(4 "In1.Cu" signal "GND")
		(6 "In2.Cu" signal "IN1")
		(8 "In3.Cu" signal "GND1")
		(10 "In4.Cu" signal "IN2")
		(12 "In5.Cu" signal "GND2")
		(14 "In6.Cu" signal "IN3")
		(16 "In7.Cu" signal "GND3")
		(18 "In8.Cu" signal "VCC")
		(20 "In9.Cu" signal "VCC1")
		(22 "In10.Cu" signal "GND4")
		(24 "In11.Cu" signal "IN4")
		(26 "In12.Cu" signal "GND5")
		(28 "In13.Cu" signal "IN5")
		(30 "In14.Cu" signal "GND6")
		(32 "In15.Cu" signal "IN6")
		(34 "In16.Cu" signal "GND7")
		(2 "B.Cu" signal "BOTTOM")
		(9 "F.Adhes" user "F.Adhesive")
		(11 "B.Adhes" user "B.Adhesive")
		(13 "F.Paste" user "Package Geometry/Pastemask Top")
		(15 "B.Paste" user "Package Geometry/Pastemask Bottom")
		(5 "F.SilkS" user "Ref Des/Silkscreen Top")
		(7 "B.SilkS" user "Ref Des/Silkscreen Bottom")
		(1 "F.Mask" user "Board Geometry/Soldermask Top")
		(3 "B.Mask" user "Board Geometry/Soldermask Bottom")
		(17 "Dwgs.User" user "User.Drawings")
		(19 "Cmts.User" user "User.Comments")
		(21 "Eco1.User" user "User.Eco1")
		(23 "Eco2.User" user "User.Eco2")
		(25 "Edge.Cuts" user "Board Geometry/Outline")
		(27 "Margin" user)
		(31 "F.CrtYd" user "Package Geometry/Place Bound Top")
		(29 "B.CrtYd" user "Package Geometry/Place Bound Bottom")
		(35 "F.Fab" user "Ref Des/Assembly Top")
		(33 "B.Fab" user "Ref Des/Assembly Bottom")
	)
	(footprint ""
		(layer "F.Cu")
		(at 205.214982 -123.785376)
		(property "Reference" "R2844"
			(at 0 0 0)
			(layer "F.SilkS")
			(hide yes)
			(effects
				(font
					(size 1.27 1.27)
				)
			)
		)
		(property "Value" ""
			(at 0 0 0)
			(layer "F.Fab")
			(effects
				(font
					(size 1.27 1.27)
				)
			)
		)
		(duplicate_pad_numbers_are_jumpers no)
		(fp_line
			(start -0.7874 -0.4064)
			(end 0.7874 -0.4064)
			(stroke
				(width 0.1524)
				(type default)
			)
			(layer "F.SilkS")
		)
		(fp_line
			(start -0.7874 0.4064)
			(end -0.7874 -0.4064)
			(stroke
				(width 0.1524)
				(type default)
			)
			(layer "F.SilkS")
		)
		(fp_line
			(start 0.7874 -0.4064)
			(end 0.7874 0.4064)
			(stroke
				(width 0.1524)
				(type default)
			)
			(layer "F.SilkS")
		)
		(fp_line
			(start 0.7874 0.4064)
			(end -0.7874 0.4064)
			(stroke
				(width 0.1524)
				(type default)
			)
			(layer "F.SilkS")
		)
		(fp_line
			(start -0.67945 -0.305054)
			(end -0.12065 -0.305054)
			(stroke
				(width 0.1)
				(type default)
			)
			(layer "F.Fab")
		)
		(fp_line
			(start -0.67945 0.3048)
			(end -0.67945 -0.305054)
			(stroke
				(width 0.1)
				(type default)
			)
			(layer "F.Fab")
		)
		(fp_line
			(start -0.12065 -0.305054)
			(end -0.12065 -0.2794)
			(stroke
				(width 0.1)
				(type default)
			)
			(layer "F.Fab")
		)
		(fp_line
			(start -0.12065 -0.2794)
			(end 0.12065 -0.2794)
			(stroke
				(width 0.1)
				(type default)
			)
			(layer "F.Fab")
		)
		(fp_line
			(start -0.12065 0.2794)
			(end -0.12065 0.3048)
			(stroke
				(width 0.1)
				(type default)
			)
			(layer "F.Fab")
		)
		(fp_line
			(start -0.12065 0.3048)
			(end -0.67945 0.3048)
			(stroke
				(width 0.1)
				(type default)
			)
			(layer "F.Fab")
		)
		(fp_line
			(start 0.120396 0.2794)
			(end -0.12065 0.2794)
			(stroke
				(width 0.1)
				(type default)
			)
			(layer "F.Fab")
		)
		(fp_line
			(start 0.120396 0.3048)
			(end 0.120396 0.2794)
			(stroke
				(width 0.1)
				(type default)
			)
			(layer "F.Fab")
		)
		(fp_line
			(start 0.12065 -0.3048)
			(end 0.67945 -0.3048)
			(stroke
				(width 0.1)
				(type default)
			)
			(layer "F.Fab")
		)
		(fp_line
			(start 0.12065 -0.2794)
			(end 0.12065 -0.3048)
			(stroke
				(width 0.1)
				(type default)
			)
			(layer "F.Fab")
		)
		(fp_line
			(start 0.67945 -0.3048)
			(end 0.67945 0.3048)
			(stroke
				(width 0.1)
				(type default)
			)
			(layer "F.Fab")
		)
		(fp_line
			(start 0.67945 0.3048)
			(end 0.120396 0.3048)
			(stroke
				(width 0.1)
				(type default)
			)
			(layer "F.Fab")
		)
		(pad "1" smd circle
			(at -0.40005 0)
			(size 0 0)
			(layers "F.Cu" "F.Mask" "F.Paste")
			(net "FM_SWB_BIC_READY_ISO_R_N")
		)
		(pad "2" smd circle
			(at 0.40005 0)
			(size 0 0)
			(layers "F.Cu" "F.Mask" "F.Paste")
			(net "FM_SWB_BIC_READY_ISO_N")
		)
	)
	(footprint ""
		(layer "F.Cu")
		(at 425.54144 -434.467508 90)
		(property "Reference" "R4164"
			(at 0 0 90)
			(layer "F.SilkS")
			(hide yes)
			(effects
				(font
					(size 1.27 1.27)
				)
			)
		)
		(property "Value" ""
			(at 0 0 90)
			(layer "F.Fab")
			(effects
				(font
					(size 1.27 1.27)
				)
			)
		)
		(duplicate_pad_numbers_are_jumpers no)
		(fp_line
			(start 0.7874 -0.4064)
			(end 0.7874 0.4064)
			(stroke
				(width 0.1524)
				(type default)
			)
			(layer "F.SilkS")
		)
		(fp_line
			(start -0.7874 -0.4064)
			(end 0.7874 -0.4064)
			(stroke
				(width 0.1524)
				(type default)
			)
			(layer "F.SilkS")
		)
		(fp_line
			(start 0.7874 0.4064)
			(end -0.7874 0.4064)
			(stroke
				(width 0.1524)
				(type default)
			)
			(layer "F.SilkS")
		)
		(fp_line
			(start -0.7874 0.4064)
			(end -0.7874 -0.4064)
			(stroke
				(width 0.1524)
				(type default)
			)
			(layer "F.SilkS")
		)
		(fp_line
			(start -0.12065 -0.305054)
			(end -0.12065 -0.2794)
			(stroke
				(width 0.1)
				(type default)
			)
			(layer "F.Fab")
		)
		(fp_line
			(start -0.67945 -0.305054)
			(end -0.12065 -0.305054)
			(stroke
				(width 0.1)
				(type default)
			)
			(layer "F.Fab")
		)
		(fp_line
			(start 0.67945 -0.3048)
			(end 0.67945 0.3048)
			(stroke
				(width 0.1)
				(type default)
			)
			(layer "F.Fab")
		)
		(fp_line
			(start 0.12065 -0.3048)
			(end 0.67945 -0.3048)
			(stroke
				(width 0.1)
				(type default)
			)
			(layer "F.Fab")
		)
		(fp_line
			(start 0.12065 -0.2794)
			(end 0.12065 -0.3048)
			(stroke
				(width 0.1)
				(type default)
			)
			(layer "F.Fab")
		)
		(fp_line
			(start -0.12065 -0.2794)
			(end 0.12065 -0.2794)
			(stroke
				(width 0.1)
				(type default)
			)
			(layer "F.Fab")
		)
		(fp_line
			(start 0.120396 0.2794)
			(end -0.12065 0.2794)
			(stroke
				(width 0.1)
				(type default)
			)
			(layer "F.Fab")
		)
		(fp_line
			(start -0.12065 0.2794)
			(end -0.12065 0.3048)
			(stroke
				(width 0.1)
				(type default)
			)
			(layer "F.Fab")
		)
		(fp_line
			(start 0.67945 0.3048)
			(end 0.120396 0.3048)
			(stroke
				(width 0.1)
				(type default)
			)
			(layer "F.Fab")
		)
		(fp_line
			(start 0.120396 0.3048)
			(end 0.120396 0.2794)
			(stroke
				(width 0.1)
				(type default)
			)
			(layer "F.Fab")
		)
		(fp_line
			(start -0.12065 0.3048)
			(end -0.67945 0.3048)
			(stroke
				(width 0.1)
				(type default)
			)
			(layer "F.Fab")
		)
		(fp_line
			(start -0.67945 0.3048)
			(end -0.67945 -0.305054)
			(stroke
				(width 0.1)
				(type default)
			)
			(layer "F.Fab")
		)
		(pad "1" smd circle
			(at -0.40005 0 90)
			(size 0 0)
			(layers "F.Cu" "F.Mask" "F.Paste")
			(net "P3V3_AUX")
		)
		(pad "2" smd circle
			(at 0.40005 0 90)
			(size 0 0)
			(layers "F.Cu" "F.Mask" "F.Paste")
			(net "GPU_3V3IO_RSVD1_N")
		)
	)
)
